(kicad_pcb
	(version 20260206)
	(generator "pcbnew")
	(generator_version "10.0")
	(general
		(thickness 1.21888)
		(legacy_teardrops no)
	)
	(paper "A4")
	(title_block
		(title "timecard-v9 — TimeCard-DC-V9_EXP.PcbDoc")
		(comment 1 "Time Appliance Project (Time Card) / footprints 218-227 of 402")
	)
	(layers
		(0 "F.Cu" signal "TOP")
		(4 "In1.Cu" signal "SGND")
		(6 "In2.Cu" signal "IN1")
		(8 "In3.Cu" signal "IN2")
		(10 "In4.Cu" signal "SGND1")
		(2 "B.Cu" signal "BOTTOM")
		(9 "F.Adhes" user "F.Adhesive")
		(11 "B.Adhes" user "B.Adhesive")
		(13 "F.Paste" user "Top Paste")
		(15 "B.Paste" user "Bottom Paste")
		(5 "F.SilkS" user "Top Overlay")
		(7 "B.SilkS" user "Bottom Overlay")
		(1 "F.Mask" user "Top Solder")
		(3 "B.Mask" user "Bottom Solder")
		(17 "Dwgs.User" user "User.Drawings")
		(19 "Cmts.User" user "User.Comments")
		(21 "Eco1.User" user "User.Eco1")
		(23 "Eco2.User" user "User.Eco2")
		(25 "Edge.Cuts" user)
		(27 "Margin" user)
		(31 "F.CrtYd" user "Top Courtyard")
		(29 "B.CrtYd" user "Bottom Courtyard")
		(35 "F.Fab" user "Top Component Center")
		(33 "B.Fab" user "Bottom Component Center")
	)
	(footprint "Vault:FP-LTST-C191KGKT-MFG"
		(layer "F.Cu")
		(at 79.4216 50.3662)
		(property "Reference" "D3"
			(at -4.571395 -0.323069 0)
			(unlocked yes)
			(layer "F.SilkS")
			(effects
				(font
					(size 0.762 0.762)
					(thickness 0.2286)
				)
			)
		)
		(property "Value" "LTST-C191KGKT"
			(at 1.2818 2.452871 0)
			(unlocked yes)
			(layer "F.SilkS")
			(hide yes)
			(effects
				(font
					(size 0.762 0.762)
					(thickness 0.2286)
				)
			)
		)
		(sheetname "02-USER_IO_STATUS")
		(sheetfile "02-USER_IO_STATUS.kicad_sch")
		(duplicate_pad_numbers_are_jumpers no)
		(fp_line
			(start -0.85 -0.775)
			(end 0.85 -0.775)
			(stroke
				(width 0.2)
				(type solid)
			)
			(layer "F.SilkS")
		)
		(fp_line
			(start -0.85 0.775)
			(end 0.85 0.775)
			(stroke
				(width 0.2)
				(type solid)
			)
			(layer "F.SilkS")
		)
		(fp_circle
			(center -1.7 0)
			(end -1.7 -0.125)
			(stroke
				(width 0.25)
				(type solid)
			)
			(fill no)
			(layer "F.SilkS")
		)
		(fp_line
			(start -1.25 -0.55)
			(end 1.25 -0.55)
			(stroke
				(width 0.2)
				(type solid)
			)
			(layer "F.CrtYd")
		)
		(fp_line
			(start -1.25 0.55)
			(end -1.25 -0.55)
			(stroke
				(width 0.2)
				(type solid)
			)
			(layer "F.CrtYd")
		)
		(fp_line
			(start -1.25 0.55)
			(end 1.25 0.55)
			(stroke
				(width 0.2)
				(type solid)
			)
			(layer "F.CrtYd")
		)
		(fp_line
			(start 1.25 0.55)
			(end 1.25 -0.55)
			(stroke
				(width 0.2)
				(type solid)
			)
			(layer "F.CrtYd")
		)
		(fp_line
			(start -1.25 -0.55)
			(end 1.25 -0.55)
			(stroke
				(width 0.2)
				(type solid)
			)
			(layer "F.Fab")
		)
		(fp_line
			(start -1.25 0.55)
			(end -1.25 -0.55)
			(stroke
				(width 0.2)
				(type solid)
			)
			(layer "F.Fab")
		)
		(fp_line
			(start -1.25 0.55)
			(end 1.25 0.55)
			(stroke
				(width 0.2)
				(type solid)
			)
			(layer "F.Fab")
		)
		(fp_line
			(start -0.5 0)
			(end 0.5 0)
			(stroke
				(width 0.1)
				(type solid)
			)
			(layer "F.Fab")
		)
		(fp_line
			(start 0 0.5)
			(end 0 -0.5)
			(stroke
				(width 0.1)
				(type solid)
			)
			(layer "F.Fab")
		)
		(fp_line
			(start 1.25 0.55)
			(end 1.25 -0.55)
			(stroke
				(width 0.2)
				(type solid)
			)
			(layer "F.Fab")
		)
		(fp_text user "${REFERENCE}"
			(at 0 0.28425 360)
			(unlocked yes)
			(layer "F.Fab")
			(effects
				(font
					(face "Arial")
					(size 0.63 0.63)
					(thickness 0.1)
				)
				(justify left bottom)
			)
		)
		(pad "1" smd rect
			(at -0.75 0)
			(size 0.8 0.8)
			(layers "F.Cu" "F.Mask" "F.Paste")
			(net "NetD3_1")
			(solder_mask_margin 0)
			(solder_paste_margin 0)
		)
		(pad "2" smd rect
			(at 0.75 0)
			(size 0.8 0.8)
			(layers "F.Cu" "F.Mask" "F.Paste")
			(net "+3.3V")
			(solder_mask_margin 0)
			(solder_paste_margin 0)
		)
	)
	(footprint "Vault:FP-D0008A-MFG"
		(layer "F.Cu")
		(at 226.0216 73.6162 90)
		(property "Reference" "U2"
			(at 0.5 2.806655 270)
			(unlocked yes)
			(layer "F.SilkS")
			(effects
				(font
					(size 0.762 0.762)
					(thickness 0.2286)
				)
				(justify left bottom)
			)
		)
		(property "Value" "INA219BIDR"
			(at -9.427445 10.9955 0)
			(unlocked yes)
			(layer "F.SilkS")
			(hide yes)
			(effects
				(font
					(size 0.762 0.762)
					(thickness 0.2286)
				)
				(justify left bottom)
			)
		)
		(sheetname "03-POWER")
		(sheetfile "03-POWER.kicad_sch")
		(duplicate_pad_numbers_are_jumpers no)
		(fp_line
			(start 1.5 -2.5)
			(end 1.5 2.5)
			(stroke
				(width 0.2)
				(type solid)
			)
			(layer "F.SilkS")
		)
		(fp_line
			(start -1.5 -2.5)
			(end 1.5 -2.5)
			(stroke
				(width 0.2)
				(type solid)
			)
			(layer "F.SilkS")
		)
		(fp_line
			(start -1.5 -2.5)
			(end -1.5 2.5)
			(stroke
				(width 0.2)
				(type solid)
			)
			(layer "F.SilkS")
		)
		(fp_line
			(start -1.5 2.5)
			(end 1.5 2.5)
			(stroke
				(width 0.2)
				(type solid)
			)
			(layer "F.SilkS")
		)
		(fp_circle
			(center -4.05 -1.905)
			(end -3.925 -1.905)
			(stroke
				(width 0.25)
				(type solid)
			)
			(fill no)
			(layer "F.SilkS")
		)
		(fp_circle
			(center -0.725 -1.725)
			(end -0.475 -1.725)
			(stroke
				(width 0.5)
				(type solid)
			)
			(fill no)
			(layer "F.SilkS")
		)
		(fp_line
			(start 3.575 -2.75)
			(end 3.575 2.75)
			(stroke
				(width 0.2)
				(type solid)
			)
			(layer "F.CrtYd")
		)
		(fp_line
			(start -3.575 -2.75)
			(end 3.575 -2.75)
			(stroke
				(width 0.2)
				(type solid)
			)
			(layer "F.CrtYd")
		)
		(fp_line
			(start -3.575 -2.75)
			(end -3.575 2.75)
			(stroke
				(width 0.2)
				(type solid)
			)
			(layer "F.CrtYd")
		)
		(fp_line
			(start -3.575 2.75)
			(end 3.575 2.75)
			(stroke
				(width 0.2)
				(type solid)
			)
			(layer "F.CrtYd")
		)
		(fp_line
			(start 3.575 -2.75)
			(end 3.575 2.75)
			(stroke
				(width 0.2)
				(type solid)
			)
			(layer "F.Fab")
		)
		(fp_line
			(start -3.575 -2.75)
			(end 3.575 -2.75)
			(stroke
				(width 0.2)
				(type solid)
			)
			(layer "F.Fab")
		)
		(fp_line
			(start -3.575 -2.75)
			(end -3.575 2.75)
			(stroke
				(width 0.2)
				(type solid)
			)
			(layer "F.Fab")
		)
		(fp_line
			(start 0 -0.5)
			(end 0 0.5)
			(stroke
				(width 0.1)
				(type solid)
			)
			(layer "F.Fab")
		)
		(fp_line
			(start -0.5 0)
			(end 0.5 0)
			(stroke
				(width 0.1)
				(type solid)
			)
			(layer "F.Fab")
		)
		(fp_line
			(start -3.575 2.75)
			(end 3.575 2.75)
			(stroke
				(width 0.2)
				(type solid)
			)
			(layer "F.Fab")
		)
		(fp_text user "${REFERENCE}"
			(at -0.00002 0.09601 90)
			(unlocked yes)
			(layer "F.Fab")
			(effects
				(font
					(face "Arial")
					(size 0.63 0.63)
					(thickness 0.1)
				)
				(justify left bottom)
			)
		)
		(pad "1" smd roundrect
			(at -2.7 -1.905 90)
			(size 1.55 0.6)
			(layers "F.Cu" "F.Mask" "F.Paste")
			(roundrect_rratio 0.085)
			(net "NetR64_1")
			(solder_mask_margin 0)
			(solder_paste_margin 0)
		)
		(pad "2" smd roundrect
			(at -2.7 -0.635 90)
			(size 1.55 0.6)
			(layers "F.Cu" "F.Mask" "F.Paste")
			(roundrect_rratio 0.085)
			(net "NetR62_1")
			(solder_mask_margin 0)
			(solder_paste_margin 0)
		)
		(pad "3" smd roundrect
			(at -2.7 0.635 90)
			(size 1.55 0.6)
			(layers "F.Cu" "F.Mask" "F.Paste")
			(roundrect_rratio 0.085)
			(net "SENS_I2C_SDA")
			(solder_mask_margin 0)
			(solder_paste_margin 0)
		)
		(pad "4" smd roundrect
			(at -2.7 1.905 90)
			(size 1.55 0.6)
			(layers "F.Cu" "F.Mask" "F.Paste")
			(roundrect_rratio 0.085)
			(net "SENS_I2C_SCL")
			(solder_mask_margin 0)
			(solder_paste_margin 0)
		)
		(pad "5" smd roundrect
			(at 2.7 1.905 90)
			(size 1.55 0.6)
			(layers "F.Cu" "F.Mask" "F.Paste")
			(roundrect_rratio 0.085)
			(net "+3.3V")
			(solder_mask_margin 0)
			(solder_paste_margin 0)
		)
		(pad "6" smd roundrect
			(at 2.7 0.635 90)
			(size 1.55 0.6)
			(layers "F.Cu" "F.Mask" "F.Paste")
			(roundrect_rratio 0.085)
			(net "GND")
			(solder_mask_margin 0)
			(solder_paste_margin 0)
		)
		(pad "7" smd roundrect
			(at 2.7 -0.635 90)
			(size 1.55 0.6)
			(layers "F.Cu" "F.Mask" "F.Paste")
			(roundrect_rratio 0.085)
			(net "+12V")
			(solder_mask_margin 0)
			(solder_paste_margin 0)
		)
		(pad "8" smd roundrect
			(at 2.7 -1.905 90)
			(size 1.55 0.6)
			(layers "F.Cu" "F.Mask" "F.Paste")
			(roundrect_rratio 0.085)
			(net "+12V_SENS")
			(solder_mask_margin 0)
			(solder_paste_margin 0)
		)
	)
	(footprint "Vault:FP-LTST-C191KGKT-MFG"
		(layer "F.Cu")
		(at 187.5716 74.5162)
		(property "Reference" "D20"
			(at 0.1786 -1.473079 0)
			(unlocked yes)
			(layer "F.SilkS")
			(effects
				(font
					(size 0.762 0.762)
					(thickness 0.2286)
				)
			)
		)
		(property "Value" "LTST-C191KGKT"
			(at -3.519671 10.67713 270)
			(unlocked yes)
			(layer "F.SilkS")
			(hide yes)
			(effects
				(font
					(size 0.762 0.762)
					(thickness 0.2286)
				)
			)
		)
		(sheetname "03-POWER")
		(sheetfile "03-POWER.kicad_sch")
		(duplicate_pad_numbers_are_jumpers no)
		(fp_line
			(start -0.85 -0.775)
			(end 0.85 -0.775)
			(stroke
				(width 0.2)
				(type solid)
			)
			(layer "F.SilkS")
		)
		(fp_line
			(start -0.85 0.775)
			(end 0.85 0.775)
			(stroke
				(width 0.2)
				(type solid)
			)
			(layer "F.SilkS")
		)
		(fp_circle
			(center -1.7 0)
			(end -1.7 -0.125)
			(stroke
				(width 0.25)
				(type solid)
			)
			(fill no)
			(layer "F.SilkS")
		)
		(fp_line
			(start -1.25 -0.55)
			(end 1.25 -0.55)
			(stroke
				(width 0.2)
				(type solid)
			)
			(layer "F.CrtYd")
		)
		(fp_line
			(start -1.25 0.55)
			(end -1.25 -0.55)
			(stroke
				(width 0.2)
				(type solid)
			)
			(layer "F.CrtYd")
		)
		(fp_line
			(start -1.25 0.55)
			(end 1.25 0.55)
			(stroke
				(width 0.2)
				(type solid)
			)
			(layer "F.CrtYd")
		)
		(fp_line
			(start 1.25 0.55)
			(end 1.25 -0.55)
			(stroke
				(width 0.2)
				(type solid)
			)
			(layer "F.CrtYd")
		)
		(fp_line
			(start -1.25 -0.55)
			(end 1.25 -0.55)
			(stroke
				(width 0.2)
				(type solid)
			)
			(layer "F.Fab")
		)
		(fp_line
			(start -1.25 0.55)
			(end -1.25 -0.55)
			(stroke
				(width 0.2)
				(type solid)
			)
			(layer "F.Fab")
		)
		(fp_line
			(start -1.25 0.55)
			(end 1.25 0.55)
			(stroke
				(width 0.2)
				(type solid)
			)
			(layer "F.Fab")
		)
		(fp_line
			(start -0.5 0)
			(end 0.5 0)
			(stroke
				(width 0.1)
				(type solid)
			)
			(layer "F.Fab")
		)
		(fp_line
			(start 0 0.5)
			(end 0 -0.5)
			(stroke
				(width 0.1)
				(type solid)
			)
			(layer "F.Fab")
		)
		(fp_line
			(start 1.25 0.55)
			(end 1.25 -0.55)
			(stroke
				(width 0.2)
				(type solid)
			)
			(layer "F.Fab")
		)
		(fp_text user "${REFERENCE}"
			(at 0 0.28425 360)
			(unlocked yes)
			(layer "F.Fab")
			(effects
				(font
					(face "Arial")
					(size 0.63 0.63)
					(thickness 0.1)
				)
				(justify left bottom)
			)
		)
		(pad "1" smd rect
			(at -0.75 0)
			(size 0.8 0.8)
			(layers "F.Cu" "F.Mask" "F.Paste")
			(net "NetD20_1")
			(solder_mask_margin 0)
			(solder_paste_margin 0)
		)
		(pad "2" smd rect
			(at 0.75 0)
			(size 0.8 0.8)
			(layers "F.Cu" "F.Mask" "F.Paste")
			(net "+3.3V")
			(solder_mask_margin 0)
			(solder_paste_margin 0)
		)
	)
	(footprint "Vault:RESC1608X55X25NL10T15"
		(layer "F.Cu")
		(at 75.4216 99.7162 180)
		(property "Reference" "R25"
			(at -0.2286 1.223079 0)
			(unlocked yes)
			(layer "F.SilkS")
			(effects
				(font
					(size 0.762 0.762)
					(thickness 0.2286)
				)
			)
		)
		(property "Value" "49.9R"
			(at -2.884671 3.186595 90)
			(unlocked yes)
			(layer "F.SilkS")
			(hide yes)
			(effects
				(font
					(size 0.762 0.762)
					(thickness 0.2286)
				)
			)
		)
		(sheetname "01-USER_IO")
		(sheetfile "01-USER_IO.kicad_sch")
		(duplicate_pad_numbers_are_jumpers no)
		(pad "1" smd rect
			(at -0.7 0 270)
			(size 0.9 0.7)
			(layers "F.Cu" "F.Mask" "F.Paste")
			(net "NetR25_1")
		)
		(pad "2" smd rect
			(at 0.7 0 270)
			(size 0.9 0.7)
			(layers "F.Cu" "F.Mask" "F.Paste")
			(net "NetAN1_1")
		)
	)
	(footprint "Vault:RESC1005X40X25NL10T10"
		(layer "F.Cu")
		(at 169.8216 110.4162)
		(property "Reference" "R124"
			(at -0.1968 -1.073069 0)
			(unlocked yes)
			(layer "F.SilkS")
			(effects
				(font
					(size 0.762 0.762)
					(thickness 0.2032)
				)
			)
		)
		(property "Value" "4.7K_1%_0402"
			(at -2.732281 8.747475 270)
			(unlocked yes)
			(layer "F.SilkS")
			(hide yes)
			(effects
				(font
					(size 0.762 0.762)
					(thickness 0.2032)
				)
			)
		)
		(sheetname "08-DIPSwitches_I2C")
		(sheetfile "08-DIPSwitches_I2C.kicad_sch")
		(duplicate_pad_numbers_are_jumpers no)
		(pad "1" smd rect
			(at -0.425 0 90)
			(size 0.6 0.65)
			(layers "F.Cu" "F.Mask" "F.Paste")
			(net "SCL")
		)
		(pad "2" smd rect
			(at 0.425 0 90)
			(size 0.6 0.65)
			(layers "F.Cu" "F.Mask" "F.Paste")
			(net "+3.3V")
		)
	)
	(footprint "SA53:SolderSocket"
		(locked yes)
		(layer "F.Cu")
		(at 116.3736 140.0162 90)
		(property "Reference" "SKT8"
			(at -3.426921 0.8766 0)
			(unlocked yes)
			(layer "F.SilkS")
			(effects
				(font
					(size 0.762 0.762)
					(thickness 0.2286)
				)
			)
		)
		(property "Value" "0332-0-43-80-18-27-10-0"
			(at -2.910071 16.1362 0)
			(unlocked yes)
			(layer "F.SilkS")
			(hide yes)
			(effects
				(font
					(size 0.762 0.762)
					(thickness 0.2286)
				)
			)
		)
		(sheetname "06-MAC")
		(sheetfile "06-MAC.kicad_sch")
		(duplicate_pad_numbers_are_jumpers no)
		(pad "1" thru_hole circle
			(at 0 0 90)
			(size 2.54 2.54)
			(drill 2.0066)
			(layers "*.Cu" "*.Mask")
			(remove_unused_layers no)
			(net "MAC_PPS_IN")
			(thermal_bridge_angle 90)
		)
	)
	(footprint "Vault:RESC1005X40X25NL10T10"
		(layer "F.Cu")
		(at 175.3216 112.0162)
		(property "Reference" "R113"
			(at 2.6032 0.126931 0)
			(unlocked yes)
			(layer "F.SilkS")
			(effects
				(font
					(size 0.762 0.762)
					(thickness 0.2032)
				)
			)
		)
		(property "Value" "4.7K_1%_0402"
			(at -2.732281 8.747475 270)
			(unlocked yes)
			(layer "F.SilkS")
			(hide yes)
			(effects
				(font
					(size 0.762 0.762)
					(thickness 0.2032)
				)
			)
		)
		(sheetname "08-DIPSwitches_I2C")
		(sheetfile "08-DIPSwitches_I2C.kicad_sch")
		(duplicate_pad_numbers_are_jumpers no)
		(pad "1" smd rect
			(at -0.425 0 90)
			(size 0.6 0.65)
			(layers "F.Cu" "F.Mask" "F.Paste")
			(net "DC_I2C_SDA")
		)
		(pad "2" smd rect
			(at 0.425 0 90)
			(size 0.6 0.65)
			(layers "F.Cu" "F.Mask" "F.Paste")
			(net "+3.3V")
		)
	)
	(footprint "Vault:RESC1005X40X25LL05T10"
		(layer "F.Cu")
		(at 194.7216 125.7162 -90)
		(property "Reference" "R175"
			(at 0.2968 2.073069 90)
			(unlocked yes)
			(layer "F.SilkS")
			(effects
				(font
					(size 0.762 0.762)
					(thickness 0.2032)
				)
			)
		)
		(property "Value" "49.9_1%_0402"
			(at -2.579871 8.798265 180)
			(unlocked yes)
			(layer "F.SilkS")
			(hide yes)
			(effects
				(font
					(size 0.762 0.762)
					(thickness 0.2032)
				)
			)
		)
		(sheetname "11-M2_RCB_MUX")
		(sheetfile "11-M2_RCB_MUX.kicad_sch")
		(duplicate_pad_numbers_are_jumpers no)
		(pad "1" smd rect
			(at -0.375 0)
			(size 0.45 0.5)
			(layers "F.Cu" "F.Mask" "F.Paste")
			(net "NetR175_1")
		)
		(pad "2" smd rect
			(at 0.375 0)
			(size 0.45 0.5)
			(layers "F.Cu" "F.Mask" "F.Paste")
			(net "GPS2_PIN12")
		)
	)
	(footprint "Vault:AMPH-901-143-6RFX_V"
		(layer "F.Cu")
		(at 69.9716 108.5782 180)
		(property "Reference" "AN2"
			(at 1.75 3.768655 0)
			(unlocked yes)
			(layer "F.SilkS")
			(effects
				(font
					(size 0.762 0.762)
					(thickness 0.2286)
				)
				(justify left bottom)
			)
		)
		(property "Value" "RF2-49B-T-00-50-G-HDW"
			(at 4.6101 -1.960245 0)
			(unlocked yes)
			(layer "F.SilkS")
			(hide yes)
			(effects
				(font
					(size 0.762 0.762)
					(thickness 0.2286)
				)
				(justify left bottom)
			)
		)
		(sheetname "01-USER_IO")
		(sheetfile "01-USER_IO.kicad_sch")
		(duplicate_pad_numbers_are_jumpers no)
		(fp_line
			(start 3.5 -1.38)
			(end 3.5 1.38)
			(stroke
				(width 0.2)
				(type solid)
			)
			(layer "F.SilkS")
		)
		(fp_line
			(start 1.38 3.5)
			(end -1.38 3.5)
			(stroke
				(width 0.2)
				(type solid)
			)
			(layer "F.SilkS")
		)
		(fp_line
			(start 1.38 -3.5)
			(end -1.38 -3.5)
			(stroke
				(width 0.2)
				(type solid)
			)
			(layer "F.SilkS")
		)
		(fp_line
			(start -3.5 -1.38)
			(end -3.5 1.38)
			(stroke
				(width 0.2)
				(type solid)
			)
			(layer "F.SilkS")
		)
		(pad "1" thru_hole rect
			(at 0 0 180)
			(size 2 2)
			(drill 1.5)
			(layers "*.Cu" "*.Mask")
			(remove_unused_layers no)
			(net "NetAN2_1")
		)
		(pad "2" thru_hole circle
			(at -2.54 -2.54 180)
			(size 2.2 2.2)
			(drill 1.7)
			(layers "*.Cu" "*.Mask")
			(remove_unused_layers no)
			(net "GND")
			(thermal_bridge_angle 90)
		)
		(pad "3" thru_hole circle
			(at -2.54 2.54 180)
			(size 2.2 2.2)
			(drill 1.7)
			(layers "*.Cu" "*.Mask")
			(remove_unused_layers no)
			(net "GND")
			(thermal_bridge_angle 90)
		)
		(pad "4" thru_hole circle
			(at 2.54 2.54 180)
			(size 2.2 2.2)
			(drill 1.7)
			(layers "*.Cu" "*.Mask")
			(remove_unused_layers no)
			(net "GND")
			(thermal_bridge_angle 90)
		)
		(pad "5" thru_hole circle
			(at 2.54 -2.54 180)
			(size 2.2 2.2)
			(drill 1.7)
			(layers "*.Cu" "*.Mask")
			(remove_unused_layers no)
			(net "GND")
			(thermal_bridge_angle 90)
		)
	)
	(footprint "Vault:RESC1005X40X25LL05T05"
		(layer "F.Cu")
		(at 84.65686 82.56371)
		(property "Reference" "R109"
			(at -2.87139 -0.073079 0)
			(unlocked yes)
			(layer "F.SilkS")
			(effects
				(font
					(size 0.762 0.762)
					(thickness 0.2286)
				)
			)
		)
		(property "Value" "4.7K_0402"
			(at -2.389351 6.513005 270)
			(unlocked yes)
			(layer "F.SilkS")
			(hide yes)
			(effects
				(font
					(size 0.762 0.762)
					(thickness 0.2032)
				)
			)
		)
		(sheetname "02-USER_IO_STATUS")
		(sheetfile "02-USER_IO_STATUS.kicad_sch")
		(duplicate_pad_numbers_are_jumpers no)
		(pad "1" smd rect
			(at -0.39999 0 90)
			(size 0.45 0.45)
			(layers "F.Cu" "F.Mask" "F.Paste")
			(net "+3.3V")
		)
		(pad "2" smd rect
			(at 0.40001 0 90)
			(size 0.45 0.45)
			(layers "F.Cu" "F.Mask" "F.Paste")
			(net "NetR40_2")
		)
	)
)
